# T6G (Grand Teton) — schematic netlist excerpt (pin names and nets, part order shuffled) for the footprints in the layout excerpt that follows; sources: Cadence DE-HDL packaged netlist, KiCad conversion of 04192023_DAF0TMB3IC0_F0TG_MB_C_brd_V02_OCP.brd

C6062  Q_CAP  0.001UF 50V 10% X7R  pkg C0402  page 177 : A = P1V2_AUX ; B = GND
PC6818  Q_CAP  22UF 16V 20% X6S  pkg C0805  page 365 : A = SW_P12V_AUX_P0V9_RETIMER_CPU1_FLT ; B = GND
C301  Q_CAP  1UF 4V 20% X6S  pkg 0201  page 334 : A = P0V9_CPU1_RT1_2A ; B = GND

(kicad_pcb
	(version 20260206)
	(generator "pcbnew")
	(generator_version "10.0")
	(general
		(thickness 1.6)
		(legacy_teardrops no)
	)
	(paper "A4")
	(title_block
		(title "04192023_DAF0TMB3IC0_F0TG_MB_C_brd_V02_OCP.brd")
		(comment 1 "Grand Teton / footprints 5923-5925 of 8354")
	)
	(layers
		(0 "F.Cu" signal "TOP")
		(4 "In1.Cu" signal "GND")
		(6 "In2.Cu" signal "IN1")
		(8 "In3.Cu" signal "GND1")
		(10 "In4.Cu" signal "IN2")
		(12 "In5.Cu" signal "GND2")
		(14 "In6.Cu" signal "IN3")
		(16 "In7.Cu" signal "GND3")
		(18 "In8.Cu" signal "VCC")
		(20 "In9.Cu" signal "VCC1")
		(22 "In10.Cu" signal "GND4")
		(24 "In11.Cu" signal "IN4")
		(26 "In12.Cu" signal "GND5")
		(28 "In13.Cu" signal "IN5")
		(30 "In14.Cu" signal "GND6")
		(32 "In15.Cu" signal "IN6")
		(34 "In16.Cu" signal "GND7")
		(2 "B.Cu" signal "BOTTOM")
		(9 "F.Adhes" user "F.Adhesive")
		(11 "B.Adhes" user "B.Adhesive")
		(13 "F.Paste" user "Package Geometry/Pastemask Top")
		(15 "B.Paste" user "Package Geometry/Pastemask Bottom")
		(5 "F.SilkS" user "Ref Des/Silkscreen Top")
		(7 "B.SilkS" user "Ref Des/Silkscreen Bottom")
		(1 "F.Mask" user "Board Geometry/Soldermask Top")
		(3 "B.Mask" user "Board Geometry/Soldermask Bottom")
		(17 "Dwgs.User" user "User.Drawings")
		(19 "Cmts.User" user "User.Comments")
		(21 "Eco1.User" user "User.Eco1")
		(23 "Eco2.User" user "User.Eco2")
		(25 "Edge.Cuts" user "Board Geometry/Outline")
		(27 "Margin" user)
		(31 "F.CrtYd" user "Package Geometry/Place Bound Top")
		(29 "B.CrtYd" user "Package Geometry/Place Bound Bottom")
		(35 "F.Fab" user "Ref Des/Assembly Top")
		(33 "B.Fab" user "Ref Des/Assembly Bottom")
	)
	(footprint ""
		(layer "B.Cu")
		(at 77.94625 -387.05028)
		(property "Reference" "C301"
			(at 0 0 0)
			(layer "B.SilkS")
			(hide yes)
			(effects
				(font
					(size 1.27 1.27)
				)
				(justify mirror)
			)
		)
		(property "Value" ""
			(at 0 0 0)
			(layer "B.Fab")
			(effects
				(font
					(size 1.27 1.27)
				)
				(justify mirror)
			)
		)
		(duplicate_pad_numbers_are_jumpers no)
		(fp_line
			(start -0.299974 -0.150114)
			(end -0.299974 0.150114)
			(stroke
				(width 0.1)
				(type default)
			)
			(layer "B.Fab")
		)
		(fp_line
			(start -0.299974 0.150114)
			(end 0.299974 0.150114)
			(stroke
				(width 0.1)
				(type default)
			)
			(layer "B.Fab")
		)
		(fp_line
			(start 0.299974 -0.150114)
			(end -0.299974 -0.150114)
			(stroke
				(width 0.1)
				(type default)
			)
			(layer "B.Fab")
		)
		(fp_line
			(start 0.299974 0.150114)
			(end 0.299974 -0.150114)
			(stroke
				(width 0.1)
				(type default)
			)
			(layer "B.Fab")
		)
		(pad "1" smd rect
			(at 0.2667 0 180)
			(size 0.3048 0.381)
			(layers "B.Cu" "B.Mask" "B.Paste")
			(net "P0V9_CPU1_RT1_2A")
		)
		(pad "2" smd rect
			(at -0.2667 0 180)
			(size 0.3048 0.381)
			(layers "B.Cu" "B.Mask" "B.Paste")
			(net "GND")
		)
	)
	(footprint ""
		(layer "B.Cu")
		(at 128.18618 -37.09543 -90)
		(property "Reference" "C6062"
			(at 0 0 90)
			(layer "B.SilkS")
			(hide yes)
			(effects
				(font
					(size 1.27 1.27)
				)
				(justify mirror)
			)
		)
		(property "Value" ""
			(at 0 0 90)
			(layer "B.Fab")
			(effects
				(font
					(size 1.27 1.27)
				)
				(justify mirror)
			)
		)
		(duplicate_pad_numbers_are_jumpers no)
		(fp_line
			(start -0.7874 0.4064)
			(end 0.7874 0.4064)
			(stroke
				(width 0.1524)
				(type default)
			)
			(layer "B.SilkS")
		)
		(fp_line
			(start 0.7874 0.4064)
			(end 0.7874 -0.4064)
			(stroke
				(width 0.1524)
				(type default)
			)
			(layer "B.SilkS")
		)
		(fp_line
			(start -0.7874 -0.4064)
			(end -0.7874 0.4064)
			(stroke
				(width 0.1524)
				(type default)
			)
			(layer "B.SilkS")
		)
		(fp_line
			(start 0.7874 -0.4064)
			(end -0.7874 -0.4064)
			(stroke
				(width 0.1524)
				(type default)
			)
			(layer "B.SilkS")
		)
		(fp_line
			(start -0.67945 0.3048)
			(end -0.120396 0.3048)
			(stroke
				(width 0.1)
				(type default)
			)
			(layer "B.Fab")
		)
		(fp_line
			(start -0.120396 0.3048)
			(end -0.120396 0.2794)
			(stroke
				(width 0.1)
				(type default)
			)
			(layer "B.Fab")
		)
		(fp_line
			(start 0.12065 0.3048)
			(end 0.67945 0.3048)
			(stroke
				(width 0.1)
				(type default)
			)
			(layer "B.Fab")
		)
		(fp_line
			(start 0.67945 0.3048)
			(end 0.67945 -0.305054)
			(stroke
				(width 0.1)
				(type default)
			)
			(layer "B.Fab")
		)
		(fp_line
			(start -0.120396 0.2794)
			(end 0.12065 0.2794)
			(stroke
				(width 0.1)
				(type default)
			)
			(layer "B.Fab")
		)
		(fp_line
			(start 0.12065 0.2794)
			(end 0.12065 0.3048)
			(stroke
				(width 0.1)
				(type default)
			)
			(layer "B.Fab")
		)
		(fp_line
			(start -0.12065 -0.2794)
			(end -0.12065 -0.3048)
			(stroke
				(width 0.1)
				(type default)
			)
			(layer "B.Fab")
		)
		(fp_line
			(start 0.12065 -0.2794)
			(end -0.12065 -0.2794)
			(stroke
				(width 0.1)
				(type default)
			)
			(layer "B.Fab")
		)
		(fp_line
			(start -0.67945 -0.3048)
			(end -0.67945 0.3048)
			(stroke
				(width 0.1)
				(type default)
			)
			(layer "B.Fab")
		)
		(fp_line
			(start -0.12065 -0.3048)
			(end -0.67945 -0.3048)
			(stroke
				(width 0.1)
				(type default)
			)
			(layer "B.Fab")
		)
		(fp_line
			(start 0.12065 -0.305054)
			(end 0.12065 -0.2794)
			(stroke
				(width 0.1)
				(type default)
			)
			(layer "B.Fab")
		)
		(fp_line
			(start 0.67945 -0.305054)
			(end 0.12065 -0.305054)
			(stroke
				(width 0.1)
				(type default)
			)
			(layer "B.Fab")
		)
		(pad "1" smd circle
			(at 0.40005 0 90)
			(size 0 0)
			(layers "B.Cu" "B.Mask" "B.Paste")
			(net "P1V2_AUX")
		)
		(pad "2" smd circle
			(at -0.40005 0 90)
			(size 0 0)
			(layers "B.Cu" "B.Mask" "B.Paste")
			(net "GND")
		)
	)
	(footprint ""
		(layer "B.Cu")
		(at 28.50388 -402.540724 -90)
		(property "Reference" "PC6818"
			(at 0 0 90)
			(layer "B.SilkS")
			(hide yes)
			(effects
				(font
					(size 1.27 1.27)
				)
				(justify mirror)
			)
		)
		(property "Value" ""
			(at 0 0 90)
			(layer "B.Fab")
			(effects
				(font
					(size 1.27 1.27)
				)
				(justify mirror)
			)
		)
		(duplicate_pad_numbers_are_jumpers no)
		(fp_line
			(start -1.524 0.762)
			(end 1.524 0.762)
			(stroke
				(width 0.1524)
				(type default)
			)
			(layer "B.SilkS")
		)
		(fp_line
			(start 1.524 0.762)
			(end 1.524 -0.762)
			(stroke
				(width 0.1524)
				(type default)
			)
			(layer "B.SilkS")
		)
		(fp_line
			(start -1.524 -0.762)
			(end -1.524 0.762)
			(stroke
				(width 0.1524)
				(type default)
			)
			(layer "B.SilkS")
		)
		(fp_line
			(start 1.524 -0.762)
			(end -1.524 -0.762)
			(stroke
				(width 0.1524)
				(type default)
			)
			(layer "B.SilkS")
		)
		(fp_line
			(start -1.1049 0.724916)
			(end -1.1049 -0.724916)
			(stroke
				(width 0.1)
				(type default)
			)
			(layer "B.Fab")
		)
		(fp_line
			(start 1.1049 0.724916)
			(end -1.1049 0.724916)
			(stroke
				(width 0.1)
				(type default)
			)
			(layer "B.Fab")
		)
		(fp_line
			(start -1.1049 -0.724916)
			(end 1.1049 -0.724916)
			(stroke
				(width 0.1)
				(type default)
			)
			(layer "B.Fab")
		)
		(fp_line
			(start 1.1049 -0.724916)
			(end 1.1049 0.724916)
			(stroke
				(width 0.1)
				(type default)
			)
			(layer "B.Fab")
		)
		(pad "1" smd rect
			(at 0.889 0 270)
			(size 1.016 1.27)
			(layers "B.Cu" "B.Mask" "B.Paste")
			(net "SW_P12V_AUX_P0V9_RETIMER_CPU1_FLT")
		)
		(pad "2" smd rect
			(at -0.889 0 270)
			(size 1.016 1.27)
			(layers "B.Cu" "B.Mask" "B.Paste")
			(net "GND")
		)
	)
)
